(kicad_pcb
	(version 20260206)
	(generator "pcbnew")
	(generator_version "10.0")
	(general
		(thickness 1.6)
		(legacy_teardrops no)
	)
	(paper "A4")
	(title_block
		(title "04192023_DAF0TMB3IC0_F0TG_MB_C_brd_V02_OCP.brd")
		(comment 1 "Grand Teton / footprints 5706-5715 of 8354")
	)
	(layers
		(0 "F.Cu" signal "TOP")
		(4 "In1.Cu" signal "GND")
		(6 "In2.Cu" signal "IN1")
		(8 "In3.Cu" signal "GND1")
		(10 "In4.Cu" signal "IN2")
		(12 "In5.Cu" signal "GND2")
		(14 "In6.Cu" signal "IN3")
		(16 "In7.Cu" signal "GND3")
		(18 "In8.Cu" signal "VCC")
		(20 "In9.Cu" signal "VCC1")
		(22 "In10.Cu" signal "GND4")
		(24 "In11.Cu" signal "IN4")
		(26 "In12.Cu" signal "GND5")
		(28 "In13.Cu" signal "IN5")
		(30 "In14.Cu" signal "GND6")
		(32 "In15.Cu" signal "IN6")
		(34 "In16.Cu" signal "GND7")
		(2 "B.Cu" signal "BOTTOM")
		(9 "F.Adhes" user "F.Adhesive")
		(11 "B.Adhes" user "B.Adhesive")
		(13 "F.Paste" user "Package Geometry/Pastemask Top")
		(15 "B.Paste" user "Package Geometry/Pastemask Bottom")
		(5 "F.SilkS" user "Ref Des/Silkscreen Top")
		(7 "B.SilkS" user "Ref Des/Silkscreen Bottom")
		(1 "F.Mask" user "Board Geometry/Soldermask Top")
		(3 "B.Mask" user "Board Geometry/Soldermask Bottom")
		(17 "Dwgs.User" user "User.Drawings")
		(19 "Cmts.User" user "User.Comments")
		(21 "Eco1.User" user "User.Eco1")
		(23 "Eco2.User" user "User.Eco2")
		(25 "Edge.Cuts" user "Board Geometry/Outline")
		(27 "Margin" user)
		(31 "F.CrtYd" user "Package Geometry/Place Bound Top")
		(29 "B.CrtYd" user "Package Geometry/Place Bound Bottom")
		(35 "F.Fab" user "Ref Des/Assembly Top")
		(33 "B.Fab" user "Ref Des/Assembly Bottom")
	)
	(footprint ""
		(layer "B.Cu")
		(at 203.045314 -77.231748)
		(property "Reference" "R3209"
			(at 0 0 0)
			(layer "B.SilkS")
			(hide yes)
			(effects
				(font
					(size 1.27 1.27)
				)
				(justify mirror)
			)
		)
		(property "Value" ""
			(at 0 0 0)
			(layer "B.Fab")
			(effects
				(font
					(size 1.27 1.27)
				)
				(justify mirror)
			)
		)
		(duplicate_pad_numbers_are_jumpers no)
		(fp_line
			(start -0.7874 -0.4064)
			(end -0.7874 0.4064)
			(stroke
				(width 0.1524)
				(type default)
			)
			(layer "B.SilkS")
		)
		(fp_line
			(start -0.7874 0.4064)
			(end 0.7874 0.4064)
			(stroke
				(width 0.1524)
				(type default)
			)
			(layer "B.SilkS")
		)
		(fp_line
			(start 0.7874 -0.4064)
			(end -0.7874 -0.4064)
			(stroke
				(width 0.1524)
				(type default)
			)
			(layer "B.SilkS")
		)
		(fp_line
			(start 0.7874 0.4064)
			(end 0.7874 -0.4064)
			(stroke
				(width 0.1524)
				(type default)
			)
			(layer "B.SilkS")
		)
		(fp_line
			(start -0.67945 -0.3048)
			(end -0.67945 0.3048)
			(stroke
				(width 0.1)
				(type default)
			)
			(layer "B.Fab")
		)
		(fp_line
			(start -0.67945 0.3048)
			(end -0.120396 0.3048)
			(stroke
				(width 0.1)
				(type default)
			)
			(layer "B.Fab")
		)
		(fp_line
			(start -0.12065 -0.3048)
			(end -0.67945 -0.3048)
			(stroke
				(width 0.1)
				(type default)
			)
			(layer "B.Fab")
		)
		(fp_line
			(start -0.12065 -0.2794)
			(end -0.12065 -0.3048)
			(stroke
				(width 0.1)
				(type default)
			)
			(layer "B.Fab")
		)
		(fp_line
			(start -0.120396 0.2794)
			(end 0.12065 0.2794)
			(stroke
				(width 0.1)
				(type default)
			)
			(layer "B.Fab")
		)
		(fp_line
			(start -0.120396 0.3048)
			(end -0.120396 0.2794)
			(stroke
				(width 0.1)
				(type default)
			)
			(layer "B.Fab")
		)
		(fp_line
			(start 0.12065 -0.305054)
			(end 0.12065 -0.2794)
			(stroke
				(width 0.1)
				(type default)
			)
			(layer "B.Fab")
		)
		(fp_line
			(start 0.12065 -0.2794)
			(end -0.12065 -0.2794)
			(stroke
				(width 0.1)
				(type default)
			)
			(layer "B.Fab")
		)
		(fp_line
			(start 0.12065 0.2794)
			(end 0.12065 0.3048)
			(stroke
				(width 0.1)
				(type default)
			)
			(layer "B.Fab")
		)
		(fp_line
			(start 0.12065 0.3048)
			(end 0.67945 0.3048)
			(stroke
				(width 0.1)
				(type default)
			)
			(layer "B.Fab")
		)
		(fp_line
			(start 0.67945 -0.305054)
			(end 0.12065 -0.305054)
			(stroke
				(width 0.1)
				(type default)
			)
			(layer "B.Fab")
		)
		(fp_line
			(start 0.67945 0.3048)
			(end 0.67945 -0.305054)
			(stroke
				(width 0.1)
				(type default)
			)
			(layer "B.Fab")
		)
		(pad "1" smd circle
			(at 0.40005 0 180)
			(size 0 0)
			(layers "B.Cu" "B.Mask" "B.Paste")
			(net "OCP_V3_2_RBT_ARB_IN_R")
		)
		(pad "2" smd circle
			(at -0.40005 0 180)
			(size 0 0)
			(layers "B.Cu" "B.Mask" "B.Paste")
			(net "OCP_V3_2_RBT_ARB_IN")
		)
	)
	(footprint ""
		(layer "B.Cu")
		(at 102.580948 -382.8796 180)
		(property "Reference" "R6733"
			(at 0 0 0)
			(layer "B.SilkS")
			(hide yes)
			(effects
				(font
					(size 1.27 1.27)
				)
				(justify mirror)
			)
		)
		(property "Value" ""
			(at 0 0 0)
			(layer "B.Fab")
			(effects
				(font
					(size 1.27 1.27)
				)
				(justify mirror)
			)
		)
		(duplicate_pad_numbers_are_jumpers no)
		(fp_line
			(start 0.32512 0.175006)
			(end 0.32512 -0.175006)
			(stroke
				(width 0.1)
				(type default)
			)
			(layer "B.Fab")
		)
		(fp_line
			(start 0.32512 -0.175006)
			(end -0.32512 -0.175006)
			(stroke
				(width 0.1)
				(type default)
			)
			(layer "B.Fab")
		)
		(fp_line
			(start -0.32512 0.175006)
			(end 0.32512 0.175006)
			(stroke
				(width 0.1)
				(type default)
			)
			(layer "B.Fab")
		)
		(fp_line
			(start -0.32512 -0.175006)
			(end -0.32512 0.175006)
			(stroke
				(width 0.1)
				(type default)
			)
			(layer "B.Fab")
		)
		(pad "1" smd rect
			(at 0.2667 0)
			(size 0.3048 0.381)
			(layers "B.Cu" "B.Mask" "B.Paste")
			(net "NCF_CPU1_P1_GND")
		)
		(pad "2" smd rect
			(at -0.2667 0 180)
			(size 0.3048 0.381)
			(layers "B.Cu" "B.Mask" "B.Paste")
			(net "GND")
		)
	)
	(footprint ""
		(layer "B.Cu")
		(at 136.936226 -390.073134 180)
		(property "Reference" "C466"
			(at 0 0 0)
			(layer "B.SilkS")
			(hide yes)
			(effects
				(font
					(size 1.27 1.27)
				)
				(justify mirror)
			)
		)
		(property "Value" ""
			(at 0 0 0)
			(layer "B.Fab")
			(effects
				(font
					(size 1.27 1.27)
				)
				(justify mirror)
			)
		)
		(duplicate_pad_numbers_are_jumpers no)
		(fp_line
			(start 1.524 0.762)
			(end 1.524 -0.762)
			(stroke
				(width 0.1524)
				(type default)
			)
			(layer "B.SilkS")
		)
		(fp_line
			(start 1.524 -0.762)
			(end -1.524 -0.762)
			(stroke
				(width 0.1524)
				(type default)
			)
			(layer "B.SilkS")
		)
		(fp_line
			(start -1.524 0.762)
			(end 1.524 0.762)
			(stroke
				(width 0.1524)
				(type default)
			)
			(layer "B.SilkS")
		)
		(fp_line
			(start -1.524 -0.762)
			(end -1.524 0.762)
			(stroke
				(width 0.1524)
				(type default)
			)
			(layer "B.SilkS")
		)
		(fp_line
			(start 1.1049 0.724916)
			(end -1.1049 0.724916)
			(stroke
				(width 0.1)
				(type default)
			)
			(layer "B.Fab")
		)
		(fp_line
			(start 1.1049 -0.724916)
			(end 1.1049 0.724916)
			(stroke
				(width 0.1)
				(type default)
			)
			(layer "B.Fab")
		)
		(fp_line
			(start -1.1049 0.724916)
			(end -1.1049 -0.724916)
			(stroke
				(width 0.1)
				(type default)
			)
			(layer "B.Fab")
		)
		(fp_line
			(start -1.1049 -0.724916)
			(end 1.1049 -0.724916)
			(stroke
				(width 0.1)
				(type default)
			)
			(layer "B.Fab")
		)
		(pad "1" smd rect
			(at 0.889 0 180)
			(size 1.016 1.27)
			(layers "B.Cu" "B.Mask" "B.Paste")
			(net "P0V9_CPU1_RT3_2A")
		)
		(pad "2" smd rect
			(at -0.889 0 180)
			(size 1.016 1.27)
			(layers "B.Cu" "B.Mask" "B.Paste")
			(net "GND")
		)
	)
	(footprint ""
		(layer "B.Cu")
		(at 153.159206 -408.517344 90)
		(property "Reference" "C6750"
			(at 0 0 90)
			(layer "B.SilkS")
			(hide yes)
			(effects
				(font
					(size 1.27 1.27)
				)
				(justify mirror)
			)
		)
		(property "Value" ""
			(at 0 0 90)
			(layer "B.Fab")
			(effects
				(font
					(size 1.27 1.27)
				)
				(justify mirror)
			)
		)
		(duplicate_pad_numbers_are_jumpers no)
		(fp_line
			(start 0.299974 -0.150114)
			(end -0.299974 -0.150114)
			(stroke
				(width 0.1)
				(type default)
			)
			(layer "B.Fab")
		)
		(fp_line
			(start -0.299974 -0.150114)
			(end -0.299974 0.150114)
			(stroke
				(width 0.1)
				(type default)
			)
			(layer "B.Fab")
		)
		(fp_line
			(start 0.299974 0.150114)
			(end 0.299974 -0.150114)
			(stroke
				(width 0.1)
				(type default)
			)
			(layer "B.Fab")
		)
		(fp_line
			(start -0.299974 0.150114)
			(end 0.299974 0.150114)
			(stroke
				(width 0.1)
				(type default)
			)
			(layer "B.Fab")
		)
		(pad "1" smd rect
			(at 0.2667 0 270)
			(size 0.3048 0.381)
			(layers "B.Cu" "B.Mask" "B.Paste")
			(net "P5E_CPU1_P3_TX_BUF_C_DN<12>")
		)
		(pad "2" smd rect
			(at -0.2667 0 270)
			(size 0.3048 0.381)
			(layers "B.Cu" "B.Mask" "B.Paste")
			(net "P5E_CPU1_P3_TX_BUF_DN<12>")
		)
	)
	(footprint ""
		(layer "B.Cu")
		(at 60.718446 -388.011162 -90)
		(property "Reference" "C198"
			(at 0 0 90)
			(layer "B.SilkS")
			(hide yes)
			(effects
				(font
					(size 1.27 1.27)
				)
				(justify mirror)
			)
		)
		(property "Value" ""
			(at 0 0 90)
			(layer "B.Fab")
			(effects
				(font
					(size 1.27 1.27)
				)
				(justify mirror)
			)
		)
		(duplicate_pad_numbers_are_jumpers no)
		(fp_line
			(start -0.299974 0.150114)
			(end 0.299974 0.150114)
			(stroke
				(width 0.1)
				(type default)
			)
			(layer "B.Fab")
		)
		(fp_line
			(start 0.299974 0.150114)
			(end 0.299974 -0.150114)
			(stroke
				(width 0.1)
				(type default)
			)
			(layer "B.Fab")
		)
		(fp_line
			(start -0.299974 -0.150114)
			(end -0.299974 0.150114)
			(stroke
				(width 0.1)
				(type default)
			)
			(layer "B.Fab")
		)
		(fp_line
			(start 0.299974 -0.150114)
			(end -0.299974 -0.150114)
			(stroke
				(width 0.1)
				(type default)
			)
			(layer "B.Fab")
		)
		(pad "1" smd rect
			(at 0.2667 0 90)
			(size 0.3048 0.381)
			(layers "B.Cu" "B.Mask" "B.Paste")
			(net "P0V9_CPU1_RT0_2A_2D")
		)
		(pad "2" smd rect
			(at -0.2667 0 90)
			(size 0.3048 0.381)
			(layers "B.Cu" "B.Mask" "B.Paste")
			(net "GND")
		)
	)
	(footprint ""
		(layer "B.Cu")
		(at 301.099728 -396.991078 90)
		(property "Reference" "C576"
			(at 0 0 90)
			(layer "B.SilkS")
			(hide yes)
			(effects
				(font
					(size 1.27 1.27)
				)
				(justify mirror)
			)
		)
		(property "Value" ""
			(at 0 0 90)
			(layer "B.Fab")
			(effects
				(font
					(size 1.27 1.27)
				)
				(justify mirror)
			)
		)
		(duplicate_pad_numbers_are_jumpers no)
		(fp_line
			(start 0.299974 -0.150114)
			(end -0.299974 -0.150114)
			(stroke
				(width 0.1)
				(type default)
			)
			(layer "B.Fab")
		)
		(fp_line
			(start -0.299974 -0.150114)
			(end -0.299974 0.150114)
			(stroke
				(width 0.1)
				(type default)
			)
			(layer "B.Fab")
		)
		(fp_line
			(start 0.299974 0.150114)
			(end 0.299974 -0.150114)
			(stroke
				(width 0.1)
				(type default)
			)
			(layer "B.Fab")
		)
		(fp_line
			(start -0.299974 0.150114)
			(end 0.299974 0.150114)
			(stroke
				(width 0.1)
				(type default)
			)
			(layer "B.Fab")
		)
		(pad "1" smd rect
			(at 0.2667 0 270)
			(size 0.3048 0.381)
			(layers "B.Cu" "B.Mask" "B.Paste")
			(net "P0V9_CPU0_RT0_2A")
		)
		(pad "2" smd rect
			(at -0.2667 0 270)
			(size 0.3048 0.381)
			(layers "B.Cu" "B.Mask" "B.Paste")
			(net "GND")
		)
	)
	(footprint ""
		(layer "B.Cu")
		(at 378.019056 -182.867554 -90)
		(property "Reference" "PC556_3"
			(at 0 0 90)
			(layer "B.SilkS")
			(hide yes)
			(effects
				(font
					(size 1.27 1.27)
				)
				(justify mirror)
			)
		)
		(property "Value" ""
			(at 0 0 90)
			(layer "B.Fab")
			(effects
				(font
					(size 1.27 1.27)
				)
				(justify mirror)
			)
		)
		(duplicate_pad_numbers_are_jumpers no)
		(fp_line
			(start -1.524 0.762)
			(end 1.524 0.762)
			(stroke
				(width 0.1524)
				(type default)
			)
			(layer "B.SilkS")
		)
		(fp_line
			(start 1.524 0.762)
			(end 1.524 -0.762)
			(stroke
				(width 0.1524)
				(type default)
			)
			(layer "B.SilkS")
		)
		(fp_line
			(start -1.524 -0.762)
			(end -1.524 0.762)
			(stroke
				(width 0.1524)
				(type default)
			)
			(layer "B.SilkS")
		)
		(fp_line
			(start 1.524 -0.762)
			(end -1.524 -0.762)
			(stroke
				(width 0.1524)
				(type default)
			)
			(layer "B.SilkS")
		)
		(fp_line
			(start -1.1049 0.724916)
			(end -1.1049 -0.724916)
			(stroke
				(width 0.1)
				(type default)
			)
			(layer "B.Fab")
		)
		(fp_line
			(start 1.1049 0.724916)
			(end -1.1049 0.724916)
			(stroke
				(width 0.1)
				(type default)
			)
			(layer "B.Fab")
		)
		(fp_line
			(start -1.1049 -0.724916)
			(end 1.1049 -0.724916)
			(stroke
				(width 0.1)
				(type default)
			)
			(layer "B.Fab")
		)
		(fp_line
			(start 1.1049 -0.724916)
			(end 1.1049 0.724916)
			(stroke
				(width 0.1)
				(type default)
			)
			(layer "B.Fab")
		)
		(pad "1" smd rect
			(at 0.889 0 270)
			(size 1.016 1.27)
			(layers "B.Cu" "B.Mask" "B.Paste")
			(net "SW_P12V_AUX_PVDDCR_CPU0_P0_FLT")
		)
		(pad "2" smd rect
			(at -0.889 0 270)
			(size 1.016 1.27)
			(layers "B.Cu" "B.Mask" "B.Paste")
			(net "GND")
		)
	)
	(footprint ""
		(layer "B.Cu")
		(at 55.778654 -386.766562 90)
		(property "Reference" "C133"
			(at 0 0 90)
			(layer "B.SilkS")
			(hide yes)
			(effects
				(font
					(size 1.27 1.27)
				)
				(justify mirror)
			)
		)
		(property "Value" ""
			(at 0 0 90)
			(layer "B.Fab")
			(effects
				(font
					(size 1.27 1.27)
				)
				(justify mirror)
			)
		)
		(duplicate_pad_numbers_are_jumpers no)
		(fp_line
			(start 0.299974 -0.150114)
			(end -0.299974 -0.150114)
			(stroke
				(width 0.1)
				(type default)
			)
			(layer "B.Fab")
		)
		(fp_line
			(start -0.299974 -0.150114)
			(end -0.299974 0.150114)
			(stroke
				(width 0.1)
				(type default)
			)
			(layer "B.Fab")
		)
		(fp_line
			(start 0.299974 0.150114)
			(end 0.299974 -0.150114)
			(stroke
				(width 0.1)
				(type default)
			)
			(layer "B.Fab")
		)
		(fp_line
			(start -0.299974 0.150114)
			(end 0.299974 0.150114)
			(stroke
				(width 0.1)
				(type default)
			)
			(layer "B.Fab")
		)
		(pad "1" smd rect
			(at 0.2667 0 270)
			(size 0.3048 0.381)
			(layers "B.Cu" "B.Mask" "B.Paste")
			(net "P1V8_CPU1_RT0_1A")
		)
		(pad "2" smd rect
			(at -0.2667 0 270)
			(size 0.3048 0.381)
			(layers "B.Cu" "B.Mask" "B.Paste")
			(net "GND")
		)
	)
	(footprint ""
		(layer "B.Cu")
		(at 167.772588 -195.8594 180)
		(property "Reference" "R1705"
			(at 0 0 0)
			(layer "B.SilkS")
			(hide yes)
			(effects
				(font
					(size 1.27 1.27)
				)
				(justify mirror)
			)
		)
		(property "Value" ""
			(at 0 0 0)
			(layer "B.Fab")
			(effects
				(font
					(size 1.27 1.27)
				)
				(justify mirror)
			)
		)
		(duplicate_pad_numbers_are_jumpers no)
		(fp_line
			(start 0.7874 0.4064)
			(end 0.7874 -0.4064)
			(stroke
				(width 0.1524)
				(type default)
			)
			(layer "B.SilkS")
		)
		(fp_line
			(start 0.7874 -0.4064)
			(end -0.7874 -0.4064)
			(stroke
				(width 0.1524)
				(type default)
			)
			(layer "B.SilkS")
		)
		(fp_line
			(start -0.7874 0.4064)
			(end 0.7874 0.4064)
			(stroke
				(width 0.1524)
				(type default)
			)
			(layer "B.SilkS")
		)
		(fp_line
			(start -0.7874 -0.4064)
			(end -0.7874 0.4064)
			(stroke
				(width 0.1524)
				(type default)
			)
			(layer "B.SilkS")
		)
		(fp_line
			(start 0.67945 0.3048)
			(end 0.67945 -0.305054)
			(stroke
				(width 0.1)
				(type default)
			)
			(layer "B.Fab")
		)
		(fp_line
			(start 0.67945 -0.305054)
			(end 0.12065 -0.305054)
			(stroke
				(width 0.1)
				(type default)
			)
			(layer "B.Fab")
		)
		(fp_line
			(start 0.12065 0.3048)
			(end 0.67945 0.3048)
			(stroke
				(width 0.1)
				(type default)
			)
			(layer "B.Fab")
		)
		(fp_line
			(start 0.12065 0.2794)
			(end 0.12065 0.3048)
			(stroke
				(width 0.1)
				(type default)
			)
			(layer "B.Fab")
		)
		(fp_line
			(start 0.12065 -0.2794)
			(end -0.12065 -0.2794)
			(stroke
				(width 0.1)
				(type default)
			)
			(layer "B.Fab")
		)
		(fp_line
			(start 0.12065 -0.305054)
			(end 0.12065 -0.2794)
			(stroke
				(width 0.1)
				(type default)
			)
			(layer "B.Fab")
		)
		(fp_line
			(start -0.120396 0.3048)
			(end -0.120396 0.2794)
			(stroke
				(width 0.1)
				(type default)
			)
			(layer "B.Fab")
		)
		(fp_line
			(start -0.120396 0.2794)
			(end 0.12065 0.2794)
			(stroke
				(width 0.1)
				(type default)
			)
			(layer "B.Fab")
		)
		(fp_line
			(start -0.12065 -0.2794)
			(end -0.12065 -0.3048)
			(stroke
				(width 0.1)
				(type default)
			)
			(layer "B.Fab")
		)
		(fp_line
			(start -0.12065 -0.3048)
			(end -0.67945 -0.3048)
			(stroke
				(width 0.1)
				(type default)
			)
			(layer "B.Fab")
		)
		(fp_line
			(start -0.67945 0.3048)
			(end -0.120396 0.3048)
			(stroke
				(width 0.1)
				(type default)
			)
			(layer "B.Fab")
		)
		(fp_line
			(start -0.67945 -0.3048)
			(end -0.67945 0.3048)
			(stroke
				(width 0.1)
				(type default)
			)
			(layer "B.Fab")
		)
		(pad "1" smd circle
			(at 0.40005 0)
			(size 0 0)
			(layers "B.Cu" "B.Mask" "B.Paste")
			(net "I3C_SPD_DDRGL_CPU1_SDA")
		)
		(pad "2" smd circle
			(at -0.40005 0)
			(size 0 0)
			(layers "B.Cu" "B.Mask" "B.Paste")
			(net "I3C_SPD_DDRG_CPU1_SDA")
		)
	)
	(footprint ""
		(layer "B.Cu")
		(at 417.546282 -396.393162 -90)
		(property "Reference" "C982"
			(at 0 0 90)
			(layer "B.SilkS")
			(hide yes)
			(effects
				(font
					(size 1.27 1.27)
				)
				(justify mirror)
			)
		)
		(property "Value" ""
			(at 0 0 90)
			(layer "B.Fab")
			(effects
				(font
					(size 1.27 1.27)
				)
				(justify mirror)
			)
		)
		(duplicate_pad_numbers_are_jumpers no)
		(fp_line
			(start -0.299974 0.150114)
			(end 0.299974 0.150114)
			(stroke
				(width 0.1)
				(type default)
			)
			(layer "B.Fab")
		)
		(fp_line
			(start 0.299974 0.150114)
			(end 0.299974 -0.150114)
			(stroke
				(width 0.1)
				(type default)
			)
			(layer "B.Fab")
		)
		(fp_line
			(start -0.299974 -0.150114)
			(end -0.299974 0.150114)
			(stroke
				(width 0.1)
				(type default)
			)
			(layer "B.Fab")
		)
		(fp_line
			(start 0.299974 -0.150114)
			(end -0.299974 -0.150114)
			(stroke
				(width 0.1)
				(type default)
			)
			(layer "B.Fab")
		)
		(pad "1" smd rect
			(at 0.2667 0 90)
			(size 0.3048 0.381)
			(layers "B.Cu" "B.Mask" "B.Paste")
			(net "P0V9_CPU0_RT2_2A")
		)
		(pad "2" smd rect
			(at -0.2667 0 90)
			(size 0.3048 0.381)
			(layers "B.Cu" "B.Mask" "B.Paste")
			(net "GND")
		)
	)
)
